(kicad_pcb
	(version 20260206)
	(generator "pcbnew")
	(generator_version "10.0")
	(general
		(thickness 1.6)
		(legacy_teardrops no)
	)
	(paper "A4")
	(title_block
		(title "panther-plus-userver — 13130-1b_20150205.brd")
		(comment 1 "Honey Badger (Wiwynn) / footprint 1214 of 1509 (DIMM3), pads 107-113 of 210")
	)
	(layers
		(0 "F.Cu" signal "TOP")
		(4 "In1.Cu" signal "L2")
		(6 "In2.Cu" signal "L3")
		(8 "In3.Cu" signal "L4")
		(10 "In4.Cu" signal "L5")
		(12 "In5.Cu" signal "L6")
		(14 "In6.Cu" signal "L7")
		(16 "In7.Cu" signal "L8")
		(18 "In8.Cu" signal "L9")
		(20 "In9.Cu" signal "L10")
		(22 "In10.Cu" signal "L11")
		(2 "B.Cu" signal "BOTTOM")
		(9 "F.Adhes" user "F.Adhesive")
		(11 "B.Adhes" user "B.Adhesive")
		(13 "F.Paste" user "Package Geometry/Pastemask Top")
		(15 "B.Paste" user "Package Geometry/Pastemask Bottom")
		(5 "F.SilkS" user "Ref Des/Silkscreen Top")
		(7 "B.SilkS" user "Ref Des/Silkscreen Bottom")
		(1 "F.Mask" user "Board Geometry/Soldermask Top")
		(3 "B.Mask" user "Board Geometry/Soldermask Bottom")
		(17 "Dwgs.User" user "User.Drawings")
		(19 "Cmts.User" user "User.Comments")
		(21 "Eco1.User" user "User.Eco1")
		(23 "Eco2.User" user "User.Eco2")
		(25 "Edge.Cuts" user "Board Geometry/Outline")
		(27 "Margin" user)
		(31 "F.CrtYd" user "Package Geometry/Place Bound Top")
		(29 "B.CrtYd" user "Package Geometry/Place Bound Bottom")
		(35 "F.Fab" user "Ref Des/Assembly Top")
		(33 "B.Fab" user "Ref Des/Assembly Bottom")
	)
	(footprint ""
		(layer "B.Cu")
		(at 159.999934 -5.790692)
		(property "Reference" "DIMM3"
			(at 0 0 0)
			(layer "B.SilkS")
			(hide yes)
			(effects
				(font
					(size 1.27 1.27)
				)
				(justify mirror)
			)
		)
		(property "Value" "DDR3-204P-142-COLAY-1-GP-U"
			(at 41.312338 -16.676878 0)
			(unlocked yes)
			(layer "B.Fab")
			(hide yes)
			(effects
				(font
					(size 1.016 1.016)
					(thickness 0.1524)
				)
				(justify mirror)
			)
		)
		(property "Device Type" "AS0A626-J8R6-7H-COLAY-1"
			(at 41.312338 -18.200878 0)
			(unlocked yes)
			(layer "B.Fab")
			(hide yes)
			(effects
				(font
					(size 1.016 1.016)
					(thickness 0.1524)
				)
				(justify mirror)
			)
		)
		(duplicate_pad_numbers_are_jumpers no)
		(pad "105" smd custom
			(at 1.949958 -4.100068 180)
			(size 0.1143 0.1143)
			(layers "B.Cu" "B.Mask" "B.Paste")
			(net "M_B_MA1")
			(options
				(clearance outline)
				(anchor circle)
			)
			(primitives
				(gr_poly
					(pts
						(xy 0 -0.9017) (xy -0.03175 -0.89916) (xy -0.0635 -0.889) (xy -0.09144 -0.87376) (xy -0.11684 -0.85344)
						(xy -0.13716 -0.82804) (xy -0.1524 -0.8001) (xy -0.16256 -0.76835) (xy -0.1651 -0.7366) (xy -0.1651 -0.44958)
						(xy -0.17272 -0.44196) (xy -0.19812 -0.4064) (xy -0.2032 -0.39624) (xy -0.20701 -0.38735) (xy -0.21209 -0.37719)
						(xy -0.2159 -0.36703) (xy -0.21844 -0.35687) (xy -0.22225 -0.34544) (xy -0.22352 -0.33528) (xy -0.22606 -0.32512)
						(xy -0.22733 -0.31369) (xy -0.22733 -0.30353) (xy -0.2286 -0.2921) (xy -0.22733 -0.28067) (xy -0.22733 -0.27051)
						(xy -0.22606 -0.25908) (xy -0.22352 -0.24892) (xy -0.22225 -0.23876) (xy -0.21844 -0.22733) (xy -0.2159 -0.21717)
						(xy -0.21209 -0.20701) (xy -0.20701 -0.19685) (xy -0.2032 -0.18796) (xy -0.19812 -0.1778) (xy -0.17272 -0.14224)
						(xy -0.1651 -0.13462) (xy -0.1651 0.7366) (xy -0.16256 0.76835) (xy -0.1524 0.8001) (xy -0.13716 0.82804)
						(xy -0.11684 0.85344) (xy -0.09144 0.87376) (xy -0.0635 0.889) (xy -0.03175 0.89916) (xy 0 0.9017)
						(xy 0.03175 0.89916) (xy 0.0635 0.889) (xy 0.09144 0.87376) (xy 0.11684 0.85344) (xy 0.13716 0.82804)
						(xy 0.1524 0.8001) (xy 0.16256 0.76835) (xy 0.1651 0.7366) (xy 0.1651 -0.13462) (xy 0.17272 -0.14224)
						(xy 0.19812 -0.1778) (xy 0.2032 -0.18796) (xy 0.20701 -0.19685) (xy 0.21209 -0.20701) (xy 0.2159 -0.21717)
						(xy 0.21844 -0.22733) (xy 0.22225 -0.23876) (xy 0.22352 -0.24892) (xy 0.22606 -0.25908) (xy 0.22733 -0.27051)
						(xy 0.22733 -0.28067) (xy 0.2286 -0.2921) (xy 0.22733 -0.30353) (xy 0.22733 -0.31369) (xy 0.22606 -0.32512)
						(xy 0.22352 -0.33528) (xy 0.22225 -0.34544) (xy 0.21844 -0.35687) (xy 0.2159 -0.36703) (xy 0.21209 -0.37719)
						(xy 0.20701 -0.38735) (xy 0.2032 -0.39624) (xy 0.19812 -0.4064) (xy 0.17272 -0.44196) (xy 0.1651 -0.44958)
						(xy 0.1651 -0.7366) (xy 0.16256 -0.76835) (xy 0.1524 -0.8001) (xy 0.13716 -0.82804) (xy 0.11684 -0.85344)
						(xy 0.09144 -0.87376) (xy 0.0635 -0.889) (xy 0.03175 -0.89916)
					)
					(width 0)
					(fill yes)
				)
			)
		)
		(pad "106" smd custom
			(at 2.249932 4.100068 180)
			(size 0.1143 0.1143)
			(layers "B.Cu" "B.Mask" "B.Paste")
			(net "M_B_MA2")
			(options
				(clearance outline)
				(anchor circle)
			)
			(primitives
				(gr_poly
					(pts
						(xy 0 -0.9017) (xy -0.03175 -0.89916) (xy -0.0635 -0.889) (xy -0.09144 -0.87376) (xy -0.11684 -0.85344)
						(xy -0.13716 -0.82804) (xy -0.1524 -0.8001) (xy -0.16256 -0.76835) (xy -0.1651 -0.7366) (xy -0.1651 0.13462)
						(xy -0.17272 0.14224) (xy -0.19812 0.1778) (xy -0.2032 0.18796) (xy -0.20701 0.19685) (xy -0.21209 0.20701)
						(xy -0.2159 0.21717) (xy -0.21844 0.22733) (xy -0.22225 0.23876) (xy -0.22352 0.24892) (xy -0.22606 0.25908)
						(xy -0.22733 0.27051) (xy -0.22733 0.28067) (xy -0.2286 0.2921) (xy -0.22733 0.30353) (xy -0.22733 0.31369)
						(xy -0.22606 0.32512) (xy -0.22352 0.33528) (xy -0.22225 0.34544) (xy -0.21844 0.35687) (xy -0.2159 0.36703)
						(xy -0.21209 0.37719) (xy -0.20701 0.38735) (xy -0.2032 0.39624) (xy -0.19812 0.4064) (xy -0.17272 0.44196)
						(xy -0.1651 0.44958) (xy -0.1651 0.7366) (xy -0.16256 0.76835) (xy -0.1524 0.8001) (xy -0.13716 0.82804)
						(xy -0.11684 0.85344) (xy -0.09144 0.87376) (xy -0.0635 0.889) (xy -0.03175 0.89916) (xy 0 0.9017)
						(xy 0.03175 0.89916) (xy 0.0635 0.889) (xy 0.09144 0.87376) (xy 0.11684 0.85344) (xy 0.13716 0.82804)
						(xy 0.1524 0.8001) (xy 0.16256 0.76835) (xy 0.1651 0.7366) (xy 0.1651 0.44958) (xy 0.17272 0.44196)
						(xy 0.19812 0.4064) (xy 0.2032 0.39624) (xy 0.20701 0.38735) (xy 0.21209 0.37719) (xy 0.2159 0.36703)
						(xy 0.21844 0.35687) (xy 0.22225 0.34544) (xy 0.22352 0.33528) (xy 0.22606 0.32512) (xy 0.22733 0.31369)
						(xy 0.22733 0.30353) (xy 0.2286 0.2921) (xy 0.22733 0.28067) (xy 0.22733 0.27051) (xy 0.22606 0.25908)
						(xy 0.22352 0.24892) (xy 0.22225 0.23876) (xy 0.21844 0.22733) (xy 0.2159 0.21717) (xy 0.21209 0.20701)
						(xy 0.20701 0.19685) (xy 0.2032 0.18796) (xy 0.19812 0.1778) (xy 0.17272 0.14224) (xy 0.1651 0.13462)
						(xy 0.1651 -0.7366) (xy 0.16256 -0.76835) (xy 0.1524 -0.8001) (xy 0.13716 -0.82804) (xy 0.11684 -0.85344)
						(xy 0.09144 -0.87376) (xy 0.0635 -0.889) (xy 0.03175 -0.89916)
					)
					(width 0)
					(fill yes)
				)
			)
		)
		(pad "107" smd custom
			(at 2.549906 -4.100068 180)
			(size 0.1143 0.1143)
			(layers "B.Cu" "B.Mask" "B.Paste")
			(net "M_B_MA0")
			(options
				(clearance outline)
				(anchor circle)
			)
			(primitives
				(gr_poly
					(pts
						(xy 0 -0.9017) (xy -0.03175 -0.89916) (xy -0.0635 -0.889) (xy -0.09144 -0.87376) (xy -0.11684 -0.85344)
						(xy -0.13716 -0.82804) (xy -0.1524 -0.8001) (xy -0.16256 -0.76835) (xy -0.1651 -0.7366) (xy -0.1651 -0.19685)
						(xy -0.17272 -0.18923) (xy -0.17907 -0.18034) (xy -0.18669 -0.17145) (xy -0.19177 -0.16256) (xy -0.19812 -0.15367)
						(xy -0.20828 -0.13335) (xy -0.21971 -0.10287) (xy -0.22225 -0.09271) (xy -0.22479 -0.08128) (xy -0.22606 -0.07112)
						(xy -0.2286 -0.05969) (xy -0.2286 -0.01651) (xy -0.22606 -0.00508) (xy -0.22479 0.00508) (xy -0.22225 0.01651)
						(xy -0.21971 0.02667) (xy -0.20828 0.05715) (xy -0.19812 0.07747) (xy -0.19177 0.08636) (xy -0.18669 0.09525)
						(xy -0.17907 0.10414) (xy -0.17272 0.11303) (xy -0.1651 0.12065) (xy -0.1651 0.7366) (xy -0.16256 0.76835)
						(xy -0.1524 0.8001) (xy -0.13716 0.82804) (xy -0.11684 0.85344) (xy -0.09144 0.87376) (xy -0.0635 0.889)
						(xy -0.03175 0.89916) (xy 0 0.9017) (xy 0.03175 0.89916) (xy 0.0635 0.889) (xy 0.09144 0.87376)
						(xy 0.11684 0.85344) (xy 0.13716 0.82804) (xy 0.1524 0.8001) (xy 0.16256 0.76835) (xy 0.1651 0.7366)
						(xy 0.1651 0.11938) (xy 0.17272 0.11176) (xy 0.19812 0.0762) (xy 0.2032 0.06604) (xy 0.20701 0.05715)
						(xy 0.21209 0.04699) (xy 0.2159 0.03683) (xy 0.21844 0.02667) (xy 0.22225 0.01524) (xy 0.22352 0.00508)
						(xy 0.22606 -0.00508) (xy 0.22733 -0.01651) (xy 0.22733 -0.02667) (xy 0.2286 -0.0381) (xy 0.22733 -0.04953)
						(xy 0.22733 -0.05969) (xy 0.22606 -0.07112) (xy 0.22352 -0.08128) (xy 0.22225 -0.09144) (xy 0.21844 -0.10287)
						(xy 0.2159 -0.11303) (xy 0.21209 -0.12319) (xy 0.20701 -0.13335) (xy 0.2032 -0.14224) (xy 0.19812 -0.1524)
						(xy 0.17272 -0.18796) (xy 0.1651 -0.19558) (xy 0.1651 -0.7366) (xy 0.16256 -0.76835) (xy 0.1524 -0.8001)
						(xy 0.13716 -0.82804) (xy 0.11684 -0.85344) (xy 0.09144 -0.87376) (xy 0.0635 -0.889) (xy 0.03175 -0.89916)
					)
					(width 0)
					(fill yes)
				)
			)
		)
		(pad "108" smd custom
			(at 2.84988 4.100068 180)
			(size 0.1143 0.1143)
			(layers "B.Cu" "B.Mask" "B.Paste")
			(net "M_B_BS1")
			(options
				(clearance outline)
				(anchor circle)
			)
			(primitives
				(gr_poly
					(pts
						(xy 0 -0.9017) (xy -0.03175 -0.89916) (xy -0.0635 -0.889) (xy -0.09144 -0.87376) (xy -0.11684 -0.85344)
						(xy -0.13716 -0.82804) (xy -0.1524 -0.8001) (xy -0.16256 -0.76835) (xy -0.1651 -0.7366) (xy -0.1651 -0.11938)
						(xy -0.17272 -0.11176) (xy -0.19812 -0.0762) (xy -0.2032 -0.06604) (xy -0.20701 -0.05715) (xy -0.21209 -0.04699)
						(xy -0.2159 -0.03683) (xy -0.21844 -0.02667) (xy -0.22225 -0.01524) (xy -0.22352 -0.00508) (xy -0.22606 0.00508)
						(xy -0.22733 0.01651) (xy -0.22733 0.02667) (xy -0.2286 0.0381) (xy -0.22733 0.04953) (xy -0.22733 0.05969)
						(xy -0.22606 0.07112) (xy -0.22352 0.08128) (xy -0.22225 0.09144) (xy -0.21844 0.10287) (xy -0.2159 0.11303)
						(xy -0.21209 0.12319) (xy -0.20701 0.13335) (xy -0.2032 0.14224) (xy -0.19812 0.1524) (xy -0.17272 0.18796)
						(xy -0.1651 0.19558) (xy -0.1651 0.7366) (xy -0.16256 0.76835) (xy -0.1524 0.8001) (xy -0.13716 0.82804)
						(xy -0.11684 0.85344) (xy -0.09144 0.87376) (xy -0.0635 0.889) (xy -0.03175 0.89916) (xy 0 0.9017)
						(xy 0.03175 0.89916) (xy 0.0635 0.889) (xy 0.09144 0.87376) (xy 0.11684 0.85344) (xy 0.13716 0.82804)
						(xy 0.1524 0.8001) (xy 0.16256 0.76835) (xy 0.1651 0.7366) (xy 0.1651 0.19685) (xy 0.17272 0.18923)
						(xy 0.17907 0.18034) (xy 0.18669 0.17145) (xy 0.19177 0.16256) (xy 0.19812 0.15367) (xy 0.20828 0.13335)
						(xy 0.21971 0.10287) (xy 0.22225 0.09271) (xy 0.22479 0.08128) (xy 0.22606 0.07112) (xy 0.2286 0.05969)
						(xy 0.2286 0.01651) (xy 0.22606 0.00508) (xy 0.22479 -0.00508) (xy 0.22225 -0.01651) (xy 0.21971 -0.02667)
						(xy 0.20828 -0.05715) (xy 0.19812 -0.07747) (xy 0.19177 -0.08636) (xy 0.18669 -0.09525) (xy 0.17907 -0.10414)
						(xy 0.17272 -0.11303) (xy 0.1651 -0.12065) (xy 0.1651 -0.7366) (xy 0.16256 -0.76835) (xy 0.1524 -0.8001)
						(xy 0.13716 -0.82804) (xy 0.11684 -0.85344) (xy 0.09144 -0.87376) (xy 0.0635 -0.889) (xy 0.03175 -0.89916)
					)
					(width 0)
					(fill yes)
				)
			)
		)
		(pad "109" smd custom
			(at 3.150108 -4.100068 180)
			(size 0.1143 0.1143)
			(layers "B.Cu" "B.Mask" "B.Paste")
			(net "PV_VDDR")
			(options
				(clearance outline)
				(anchor circle)
			)
			(primitives
				(gr_poly
					(pts
						(xy 0 -0.9017) (xy -0.03175 -0.89916) (xy -0.0635 -0.889) (xy -0.09144 -0.87376) (xy -0.11684 -0.85344)
						(xy -0.13716 -0.82804) (xy -0.1524 -0.8001) (xy -0.16256 -0.76835) (xy -0.1651 -0.7366) (xy -0.1651 -0.44958)
						(xy -0.17272 -0.44196) (xy -0.19812 -0.4064) (xy -0.2032 -0.39624) (xy -0.20701 -0.38735) (xy -0.21209 -0.37719)
						(xy -0.2159 -0.36703) (xy -0.21844 -0.35687) (xy -0.22225 -0.34544) (xy -0.22352 -0.33528) (xy -0.22606 -0.32512)
						(xy -0.22733 -0.31369) (xy -0.22733 -0.30353) (xy -0.2286 -0.2921) (xy -0.22733 -0.28067) (xy -0.22733 -0.27051)
						(xy -0.22606 -0.25908) (xy -0.22352 -0.24892) (xy -0.22225 -0.23876) (xy -0.21844 -0.22733) (xy -0.2159 -0.21717)
						(xy -0.21209 -0.20701) (xy -0.20701 -0.19685) (xy -0.2032 -0.18796) (xy -0.19812 -0.1778) (xy -0.17272 -0.14224)
						(xy -0.1651 -0.13462) (xy -0.1651 0.7366) (xy -0.16256 0.76835) (xy -0.1524 0.8001) (xy -0.13716 0.82804)
						(xy -0.11684 0.85344) (xy -0.09144 0.87376) (xy -0.0635 0.889) (xy -0.03175 0.89916) (xy 0 0.9017)
						(xy 0.03175 0.89916) (xy 0.0635 0.889) (xy 0.09144 0.87376) (xy 0.11684 0.85344) (xy 0.13716 0.82804)
						(xy 0.1524 0.8001) (xy 0.16256 0.76835) (xy 0.1651 0.7366) (xy 0.1651 -0.13462) (xy 0.17272 -0.14224)
						(xy 0.19812 -0.1778) (xy 0.2032 -0.18796) (xy 0.20701 -0.19685) (xy 0.21209 -0.20701) (xy 0.2159 -0.21717)
						(xy 0.21844 -0.22733) (xy 0.22225 -0.23876) (xy 0.22352 -0.24892) (xy 0.22606 -0.25908) (xy 0.22733 -0.27051)
						(xy 0.22733 -0.28067) (xy 0.2286 -0.2921) (xy 0.22733 -0.30353) (xy 0.22733 -0.31369) (xy 0.22606 -0.32512)
						(xy 0.22352 -0.33528) (xy 0.22225 -0.34544) (xy 0.21844 -0.35687) (xy 0.2159 -0.36703) (xy 0.21209 -0.37719)
						(xy 0.20701 -0.38735) (xy 0.2032 -0.39624) (xy 0.19812 -0.4064) (xy 0.17272 -0.44196) (xy 0.1651 -0.44958)
						(xy 0.1651 -0.7366) (xy 0.16256 -0.76835) (xy 0.1524 -0.8001) (xy 0.13716 -0.82804) (xy 0.11684 -0.85344)
						(xy 0.09144 -0.87376) (xy 0.0635 -0.889) (xy 0.03175 -0.89916)
					)
					(width 0)
					(fill yes)
				)
			)
		)
		(pad "110" smd custom
			(at 3.450082 4.100068 180)
			(size 0.1143 0.1143)
			(layers "B.Cu" "B.Mask" "B.Paste")
			(net "PV_VDDR")
			(options
				(clearance outline)
				(anchor circle)
			)
			(primitives
				(gr_poly
					(pts
						(xy 0 -0.9017) (xy -0.03175 -0.89916) (xy -0.0635 -0.889) (xy -0.09144 -0.87376) (xy -0.11684 -0.85344)
						(xy -0.13716 -0.82804) (xy -0.1524 -0.8001) (xy -0.16256 -0.76835) (xy -0.1651 -0.7366) (xy -0.1651 0.13462)
						(xy -0.17272 0.14224) (xy -0.19812 0.1778) (xy -0.2032 0.18796) (xy -0.20701 0.19685) (xy -0.21209 0.20701)
						(xy -0.2159 0.21717) (xy -0.21844 0.22733) (xy -0.22225 0.23876) (xy -0.22352 0.24892) (xy -0.22606 0.25908)
						(xy -0.22733 0.27051) (xy -0.22733 0.28067) (xy -0.2286 0.2921) (xy -0.22733 0.30353) (xy -0.22733 0.31369)
						(xy -0.22606 0.32512) (xy -0.22352 0.33528) (xy -0.22225 0.34544) (xy -0.21844 0.35687) (xy -0.2159 0.36703)
						(xy -0.21209 0.37719) (xy -0.20701 0.38735) (xy -0.2032 0.39624) (xy -0.19812 0.4064) (xy -0.17272 0.44196)
						(xy -0.1651 0.44958) (xy -0.1651 0.7366) (xy -0.16256 0.76835) (xy -0.1524 0.8001) (xy -0.13716 0.82804)
						(xy -0.11684 0.85344) (xy -0.09144 0.87376) (xy -0.0635 0.889) (xy -0.03175 0.89916) (xy 0 0.9017)
						(xy 0.03175 0.89916) (xy 0.0635 0.889) (xy 0.09144 0.87376) (xy 0.11684 0.85344) (xy 0.13716 0.82804)
						(xy 0.1524 0.8001) (xy 0.16256 0.76835) (xy 0.1651 0.7366) (xy 0.1651 0.44958) (xy 0.17272 0.44196)
						(xy 0.19812 0.4064) (xy 0.2032 0.39624) (xy 0.20701 0.38735) (xy 0.21209 0.37719) (xy 0.2159 0.36703)
						(xy 0.21844 0.35687) (xy 0.22225 0.34544) (xy 0.22352 0.33528) (xy 0.22606 0.32512) (xy 0.22733 0.31369)
						(xy 0.22733 0.30353) (xy 0.2286 0.2921) (xy 0.22733 0.28067) (xy 0.22733 0.27051) (xy 0.22606 0.25908)
						(xy 0.22352 0.24892) (xy 0.22225 0.23876) (xy 0.21844 0.22733) (xy 0.2159 0.21717) (xy 0.21209 0.20701)
						(xy 0.20701 0.19685) (xy 0.2032 0.18796) (xy 0.19812 0.1778) (xy 0.17272 0.14224) (xy 0.1651 0.13462)
						(xy 0.1651 -0.7366) (xy 0.16256 -0.76835) (xy 0.1524 -0.8001) (xy 0.13716 -0.82804) (xy 0.11684 -0.85344)
						(xy 0.09144 -0.87376) (xy 0.0635 -0.889) (xy 0.03175 -0.89916)
					)
					(width 0)
					(fill yes)
				)
			)
		)
		(pad "111" smd custom
			(at 3.750056 -4.100068 180)
			(size 0.1143 0.1143)
			(layers "B.Cu" "B.Mask" "B.Paste")
			(net "M_B_CK_DP0")
			(options
				(clearance outline)
				(anchor circle)
			)
			(primitives
				(gr_poly
					(pts
						(xy 0 -0.9017) (xy -0.03175 -0.89916) (xy -0.0635 -0.889) (xy -0.09144 -0.87376) (xy -0.11684 -0.85344)
						(xy -0.13716 -0.82804) (xy -0.1524 -0.8001) (xy -0.16256 -0.76835) (xy -0.1651 -0.7366) (xy -0.1651 -0.19685)
						(xy -0.17272 -0.18923) (xy -0.17907 -0.18034) (xy -0.18669 -0.17145) (xy -0.19177 -0.16256) (xy -0.19812 -0.15367)
						(xy -0.20828 -0.13335) (xy -0.21971 -0.10287) (xy -0.22225 -0.09271) (xy -0.22479 -0.08128) (xy -0.22606 -0.07112)
						(xy -0.2286 -0.05969) (xy -0.2286 -0.01651) (xy -0.22606 -0.00508) (xy -0.22479 0.00508) (xy -0.22225 0.01651)
						(xy -0.21971 0.02667) (xy -0.20828 0.05715) (xy -0.19812 0.07747) (xy -0.19177 0.08636) (xy -0.18669 0.09525)
						(xy -0.17907 0.10414) (xy -0.17272 0.11303) (xy -0.1651 0.12065) (xy -0.1651 0.7366) (xy -0.16256 0.76835)
						(xy -0.1524 0.8001) (xy -0.13716 0.82804) (xy -0.11684 0.85344) (xy -0.09144 0.87376) (xy -0.0635 0.889)
						(xy -0.03175 0.89916) (xy 0 0.9017) (xy 0.03175 0.89916) (xy 0.0635 0.889) (xy 0.09144 0.87376)
						(xy 0.11684 0.85344) (xy 0.13716 0.82804) (xy 0.1524 0.8001) (xy 0.16256 0.76835) (xy 0.1651 0.7366)
						(xy 0.1651 0.11938) (xy 0.17272 0.11176) (xy 0.19812 0.0762) (xy 0.2032 0.06604) (xy 0.20701 0.05715)
						(xy 0.21209 0.04699) (xy 0.2159 0.03683) (xy 0.21844 0.02667) (xy 0.22225 0.01524) (xy 0.22352 0.00508)
						(xy 0.22606 -0.00508) (xy 0.22733 -0.01651) (xy 0.22733 -0.02667) (xy 0.2286 -0.0381) (xy 0.22733 -0.04953)
						(xy 0.22733 -0.05969) (xy 0.22606 -0.07112) (xy 0.22352 -0.08128) (xy 0.22225 -0.09144) (xy 0.21844 -0.10287)
						(xy 0.2159 -0.11303) (xy 0.21209 -0.12319) (xy 0.20701 -0.13335) (xy 0.2032 -0.14224) (xy 0.19812 -0.1524)
						(xy 0.17272 -0.18796) (xy 0.1651 -0.19558) (xy 0.1651 -0.7366) (xy 0.16256 -0.76835) (xy 0.1524 -0.8001)
						(xy 0.13716 -0.82804) (xy 0.11684 -0.85344) (xy 0.09144 -0.87376) (xy 0.0635 -0.889) (xy 0.03175 -0.89916)
					)
					(width 0)
					(fill yes)
				)
			)
		)
	)
)
